# S9S_MB_2U (Grand Teton) — schematic netlist excerpt (pin names and nets, part order shuffled) for the footprints in the layout excerpt that follows; sources: Cadence DE-HDL packaged netlist, KiCad conversion of 03242023_DA0F0TMBIJ0_F0T_Motherboard_J_brd_V01_OCP.brd

PU9  IR3889MTRPBF  IC  pkg QFN22_6X5  page 259
  ILIM  = P3V3_AUX_ILIM
  PGOOD  = PWRGD_P3V3_AUX
  VIN  = P12V_AUX
  \vcc||ldo\  = P3V3_AUX_VCC
  VDRV  = P3V3_AUX_VDRV
  GATEL1  = NC_PU9_3
  PGND  = GND
  SW  = SW_P3V3_AUX_SW
  PVIN  = SW_P3V3_AUX_FLT
  PHASE  = SW_P3V3_AUX_BOOTR
  BOOT  = SW_P3V3_AUX_BOOT
  EN  = P3V3_AUX_EN
  NC1  = P3V3_AUX_VOS
  \ss||latch\  = P3V3_AUX_SS
  FB  = P3V3_AUX_FB
  VSENM  = GND
  AGND  = GND
  NC2  = NC_PU9_1
  NC3  = NC_PU9_2
  NC4  = NC_HICCUP
  \ton||mode\  = P3V3_AUX_MODE
  GATEL2  = NC_PU9_4

(kicad_pcb
	(version 20260206)
	(generator "pcbnew")
	(generator_version "10.0")
	(general
		(thickness 1.6)
		(legacy_teardrops no)
	)
	(paper "A4")
	(title_block
		(title "03242023_DA0F0TMBIJ0_F0T_Motherboard_J_brd_V01_OCP.brd")
		(comment 1 "Grand Teton / footprint 2145 of 6105 (PU9), pads 1-22 of 22")
	)
	(layers
		(0 "F.Cu" signal "TOP")
		(4 "In1.Cu" signal "GND")
		(6 "In2.Cu" signal "IN1")
		(8 "In3.Cu" signal "GND1")
		(10 "In4.Cu" signal "IN2")
		(12 "In5.Cu" signal "GND2")
		(14 "In6.Cu" signal "IN3")
		(16 "In7.Cu" signal "GND3")
		(18 "In8.Cu" signal "VCC")
		(20 "In9.Cu" signal "VCC1")
		(22 "In10.Cu" signal "GND4")
		(24 "In11.Cu" signal "IN4")
		(26 "In12.Cu" signal "GND5")
		(28 "In13.Cu" signal "IN5")
		(30 "In14.Cu" signal "GND6")
		(32 "In15.Cu" signal "IN6")
		(34 "In16.Cu" signal "GND7")
		(2 "B.Cu" signal "BOTTOM")
		(9 "F.Adhes" user "F.Adhesive")
		(11 "B.Adhes" user "B.Adhesive")
		(13 "F.Paste" user "Package Geometry/Pastemask Top")
		(15 "B.Paste" user "Package Geometry/Pastemask Bottom")
		(5 "F.SilkS" user "Ref Des/Silkscreen Top")
		(7 "B.SilkS" user "Ref Des/Silkscreen Bottom")
		(1 "F.Mask" user "Board Geometry/Soldermask Top")
		(3 "B.Mask" user "Board Geometry/Soldermask Bottom")
		(17 "Dwgs.User" user "User.Drawings")
		(19 "Cmts.User" user "User.Comments")
		(21 "Eco1.User" user "User.Eco1")
		(23 "Eco2.User" user "User.Eco2")
		(25 "Edge.Cuts" user "Board Geometry/Outline")
		(27 "Margin" user)
		(31 "F.CrtYd" user "Package Geometry/Place Bound Top")
		(29 "B.CrtYd" user "Package Geometry/Place Bound Bottom")
		(35 "F.Fab" user "Ref Des/Assembly Top")
		(33 "B.Fab" user "Ref Des/Assembly Bottom")
	)
	(footprint ""
		(layer "F.Cu")
		(at 448.418966 -73.02754)
		(property "Reference" "PU9"
			(at -8.757666 -1.038098 0)
			(unlocked yes)
			(layer "F.SilkS")
			(effects
				(font
					(size 0.7874 0.5842)
					(thickness 0.1524)
				)
				(justify left)
			)
		)
		(property "Value" ""
			(at 0 0 0)
			(layer "F.Fab")
			(effects
				(font
					(size 1.27 1.27)
				)
			)
		)
		(duplicate_pad_numbers_are_jumpers no)
		(pad "1" smd rect
			(at -2.362708 -2.249932 90)
			(size 0.2794 0.5842)
			(layers "F.Cu" "F.Mask" "F.Paste")
			(net "P3V3_AUX_ILIM")
		)
		(pad "2" smd rect
			(at -2.350008 -1.75006 90)
			(size 0.2794 0.6096)
			(layers "F.Cu" "F.Mask" "F.Paste")
			(net "PWRGD_P3V3_AUX")
		)
		(pad "3" smd rect
			(at -2.350008 -1.249934 90)
			(size 0.2794 0.6096)
			(layers "F.Cu" "F.Mask" "F.Paste")
			(net "P12V_AUX")
		)
		(pad "4" smd rect
			(at -2.350008 -0.750062 90)
			(size 0.2794 0.6096)
			(layers "F.Cu" "F.Mask" "F.Paste")
			(net "P3V3_AUX_VCC")
		)
		(pad "5" smd rect
			(at -2.350008 -0.249936 90)
			(size 0.2794 0.6096)
			(layers "F.Cu" "F.Mask" "F.Paste")
			(net "P3V3_AUX_VDRV")
		)
		(pad "6" smd rect
			(at -2.350008 0.249936 90)
			(size 0.2794 0.6096)
			(layers "F.Cu" "F.Mask" "F.Paste")
			(net "NC_PU9_3")
		)
		(pad "7_10-19" smd circle
			(at 0 0.062484 270)
			(size 0 0)
			(layers "F.Cu" "F.Mask" "F.Paste")
			(net "GND")
		)
		(pad "11_18" smd circle
			(at 0 2.712466 270)
			(size 0 0)
			(layers "F.Cu" "F.Mask" "F.Paste")
			(net "SW_P3V3_AUX_SW")
		)
		(pad "20_24" smd circle
			(at 1.787906 0.749808)
			(size 0 0)
			(layers "F.Cu" "F.Mask" "F.Paste")
			(net "SW_P3V3_AUX_FLT")
		)
		(pad "25" smd rect
			(at 2.350008 -0.750062 90)
			(size 0.2794 0.6096)
			(layers "F.Cu" "F.Mask" "F.Paste")
			(net "SW_P3V3_AUX_BOOTR")
		)
		(pad "26" smd rect
			(at 2.350008 -1.249934 90)
			(size 0.2794 0.6096)
			(layers "F.Cu" "F.Mask" "F.Paste")
			(net "SW_P3V3_AUX_BOOT")
		)
		(pad "27" smd rect
			(at 2.350008 -1.75006 90)
			(size 0.2794 0.6096)
			(layers "F.Cu" "F.Mask" "F.Paste")
			(net "P3V3_AUX_EN")
		)
		(pad "28" smd rect
			(at 2.362708 -2.249932 90)
			(size 0.2794 0.5842)
			(layers "F.Cu" "F.Mask" "F.Paste")
			(net "P3V3_AUX_VOS")
		)
		(pad "29" smd rect
			(at 1.75006 -2.887726)
			(size 0.2794 0.5842)
			(layers "F.Cu" "F.Mask" "F.Paste")
			(net "P3V3_AUX_SS")
		)
		(pad "30" smd rect
			(at 1.249934 -2.875026)
			(size 0.2794 0.6096)
			(layers "F.Cu" "F.Mask" "F.Paste")
			(net "P3V3_AUX_FB")
		)
		(pad "31" smd rect
			(at 0.750062 -2.875026)
			(size 0.2794 0.6096)
			(layers "F.Cu" "F.Mask" "F.Paste")
			(net "GND")
		)
		(pad "32" smd rect
			(at 0.249936 -2.875026)
			(size 0.2794 0.6096)
			(layers "F.Cu" "F.Mask" "F.Paste")
			(net "GND")
		)
		(pad "33" smd rect
			(at -0.249936 -2.875026)
			(size 0.2794 0.6096)
			(layers "F.Cu" "F.Mask" "F.Paste")
			(net "NC_PU9_1")
		)
		(pad "34" smd rect
			(at -0.750062 -2.875026)
			(size 0.2794 0.6096)
			(layers "F.Cu" "F.Mask" "F.Paste")
			(net "NC_PU9_2")
		)
		(pad "35" smd rect
			(at -1.249934 -2.875026)
			(size 0.2794 0.6096)
			(layers "F.Cu" "F.Mask" "F.Paste")
			(net "NC_HICCUP")
		)
		(pad "36" smd rect
			(at -1.75006 -2.887726)
			(size 0.2794 0.5842)
			(layers "F.Cu" "F.Mask" "F.Paste")
			(net "P3V3_AUX_MODE")
		)
		(pad "37" smd rect
			(at -1.549908 0.150114 90)
			(size 0.3048 0.508)
			(layers "F.Cu" "F.Mask" "F.Paste")
			(net "NC_PU9_4")
		)
	)
)
